# BASEBOARD_FAB2 (Tioga Pass) — schematic netlist excerpt (pin names and nets, part order shuffled) for the footprints in the layout excerpt that follows; sources: Cadence DE-HDL packaged netlist, KiCad conversion of Wiwynn_Tioga_Pass_MB.brd

EU1B1  PXM1310B  IC  pkg QFN  page 226
  BPWM1  = NC
  DNC(0)  = NC
  APWM3  = NC
  APWM2  = VR_PVDDQ_KLM_PWM2
  APWM1  = VR_PVDDQ_KLM_PWM1
  SDA  = SMB_VR_STBY_LVC3_SDA
  SCL  = SMB_VR_STBY_LVC3_SCL
  RESET_N  = NC
  AVRRDY  = PWRGD_PVDDQ_KLM_R
  AVREN  = VR_PVDDQ_KLM_VREN
  VRHOT_N  = IRQ_PVDDQ_KLM_VRHOT_LVT3_R_N
  PINALRT_N  = NC
  MP0  = PU_VR_PVDDQ_KLM_FAULT1
  MP1  = NC_PVDDQ_KLM_GP1
  VCLK  = SVID_CLK_PVDDQ_KLM
  VDIO  = SVID_VDIO_PVDDQ_KLM
  VALRT_N  = SVID_ALERT_PVDDQ_KLM
  MP2  = NC_PVDDQ_KLM_GP0
  AVSEN  = VR_PVDDQ_KLM_AVSP
  AVREF  = VSENSE_PVDDQ_KLM_N
  AIREF1  = VR_PVDDQ_KLM_AIREF1
  AISEN1  = ISENSE_PVDDQ_KLM_PH1_IMON
  AIREF2  = VR_PVDDQ_KLM_AIREF2
  AISEN2  = ISENSE_PVDDQ_KLM_PH2_IMON
  AIREF3  = NC
  AISEN3  = NC
  GND  = GND
  DNC(1)  = NC
  BVSEN  = NC
  BVREF  = NC
  BIREF1  = NC
  BISEN1  = GND
  XADDR2  = VR_PVDDQ_KLM_XADDR2
  BTSEN  = NC
  ATSEN  = A_TSENSE_PVDDQ_KLM
  XADDR1  = VR_PVDDQ_KLM_XADDR1
  VINSEN  = VR_PVDDQ_KLM_VINSEN
  IINSEN  = VR_PVDDQ_KLM_AIINSEN
  VDD  = VR_PVDDQ_KLM_VDD
  VD12  = VR_PVDDQ_KLM_VD12
  THPAD  = GND

(kicad_pcb
	(version 20260206)
	(generator "pcbnew")
	(generator_version "10.0")
	(general
		(thickness 1.6)
		(legacy_teardrops no)
	)
	(paper "A4")
	(title_block
		(title "Wiwynn_Tioga_Pass_MB.brd")
		(comment 1 "Tioga Pass / footprint 1727 of 4770 (EU1B1), pads 35-41 of 41")
	)
	(layers
		(0 "F.Cu" signal "TOP")
		(4 "In1.Cu" signal "L2GND")
		(6 "In2.Cu" signal "L3")
		(8 "In3.Cu" signal "L4GND")
		(10 "In4.Cu" signal "L5")
		(12 "In5.Cu" signal "L6GND")
		(14 "In6.Cu" signal "L7VCC")
		(16 "In7.Cu" signal "L8VCC")
		(18 "In8.Cu" signal "L9GND")
		(20 "In9.Cu" signal "L10")
		(22 "In10.Cu" signal "L11GND")
		(24 "In11.Cu" signal "L12")
		(26 "In12.Cu" signal "L13GND")
		(2 "B.Cu" signal "BOTTOM")
		(9 "F.Adhes" user "F.Adhesive")
		(11 "B.Adhes" user "B.Adhesive")
		(13 "F.Paste" user "Package Geometry/Pastemask Top")
		(15 "B.Paste" user "Package Geometry/Pastemask Bottom")
		(5 "F.SilkS" user "Ref Des/Silkscreen Top")
		(7 "B.SilkS" user "Ref Des/Silkscreen Bottom")
		(1 "F.Mask" user "Board Geometry/Soldermask Top")
		(3 "B.Mask" user "Board Geometry/Soldermask Bottom")
		(17 "Dwgs.User" user "User.Drawings")
		(19 "Cmts.User" user "User.Comments")
		(21 "Eco1.User" user "User.Eco1")
		(23 "Eco2.User" user "User.Eco2")
		(25 "Edge.Cuts" user "Board Geometry/Outline")
		(27 "Margin" user)
		(31 "F.CrtYd" user "Package Geometry/Place Bound Top")
		(29 "B.CrtYd" user "Package Geometry/Place Bound Bottom")
		(35 "F.Fab" user "Ref Des/Assembly Top")
		(33 "B.Fab" user "Ref Des/Assembly Bottom")
	)
	(footprint ""
		(layer "F.Cu")
		(at 2.0574 -127.9652 -90)
		(property "Reference" "EU1B1"
			(at 3.76047 4.0132 0)
			(unlocked yes)
			(layer "F.SilkS")
			(effects
				(font
					(size 0.7874 0.5842)
					(thickness 0.1524)
				)
				(justify left)
			)
		)
		(property "Value" ""
			(at 0 0 270)
			(layer "F.Fab")
			(effects
				(font
					(size 1.27 1.27)
				)
			)
		)
		(duplicate_pad_numbers_are_jumpers no)
		(pad "35" smd custom
			(at 0.199898 -2.4511 270)
			(size 0.0508 0.0508)
			(layers "F.Cu" "F.Mask" "F.Paste")
			(net "A_TSENSE_PVDDQ_KLM")
			(options
				(clearance outline)
				(anchor circle)
			)
			(primitives
				(gr_poly
					(pts
						(arc
							(start 0.1016 0.254)
							(mid 0 0.3556)
							(end -0.1016 0.254)
						)
						(xy -0.1016 -0.3556) (xy 0.1016 -0.3556)
					)
					(width 0)
					(fill yes)
				)
			)
		)
		(pad "36" smd custom
			(at -0.199898 -2.4511 270)
			(size 0.0508 0.0508)
			(layers "F.Cu" "F.Mask" "F.Paste")
			(net "VR_PVDDQ_KLM_XADDR1")
			(options
				(clearance outline)
				(anchor circle)
			)
			(primitives
				(gr_poly
					(pts
						(arc
							(start 0.1016 0.254)
							(mid 0 0.3556)
							(end -0.1016 0.254)
						)
						(xy -0.1016 -0.3556) (xy 0.1016 -0.3556)
					)
					(width 0)
					(fill yes)
				)
			)
		)
		(pad "37" smd custom
			(at -0.599948 -2.4511 270)
			(size 0.0508 0.0508)
			(layers "F.Cu" "F.Mask" "F.Paste")
			(net "VR_PVDDQ_KLM_VINSEN")
			(options
				(clearance outline)
				(anchor circle)
			)
			(primitives
				(gr_poly
					(pts
						(arc
							(start 0.1016 0.254)
							(mid 0 0.3556)
							(end -0.1016 0.254)
						)
						(xy -0.1016 -0.3556) (xy 0.1016 -0.3556)
					)
					(width 0)
					(fill yes)
				)
			)
		)
		(pad "38" smd custom
			(at -0.999998 -2.4511 270)
			(size 0.0508 0.0508)
			(layers "F.Cu" "F.Mask" "F.Paste")
			(net "VR_PVDDQ_KLM_AIINSEN")
			(options
				(clearance outline)
				(anchor circle)
			)
			(primitives
				(gr_poly
					(pts
						(arc
							(start 0.1016 0.254)
							(mid 0 0.3556)
							(end -0.1016 0.254)
						)
						(xy -0.1016 -0.3556) (xy 0.1016 -0.3556)
					)
					(width 0)
					(fill yes)
				)
			)
		)
		(pad "39" smd custom
			(at -1.400048 -2.4511 270)
			(size 0.0508 0.0508)
			(layers "F.Cu" "F.Mask" "F.Paste")
			(net "VR_PVDDQ_KLM_VDD")
			(options
				(clearance outline)
				(anchor circle)
			)
			(primitives
				(gr_poly
					(pts
						(arc
							(start 0.1016 0.254)
							(mid 0 0.3556)
							(end -0.1016 0.254)
						)
						(xy -0.1016 -0.3556) (xy 0.1016 -0.3556)
					)
					(width 0)
					(fill yes)
				)
			)
		)
		(pad "40" smd custom
			(at -1.800098 -2.4511 270)
			(size 0.0508 0.0508)
			(layers "F.Cu" "F.Mask" "F.Paste")
			(net "VR_PVDDQ_KLM_VD12")
			(options
				(clearance outline)
				(anchor circle)
			)
			(primitives
				(gr_poly
					(pts
						(arc
							(start 0.1016 0.254)
							(mid 0 0.3556)
							(end -0.1016 0.254)
						)
						(xy -0.1016 -0.3556) (xy 0.1016 -0.3556)
					)
					(width 0)
					(fill yes)
				)
			)
		)
		(pad "41" smd rect
			(at 0 0 270)
			(size 3.683 3.683)
			(layers "F.Cu" "F.Mask" "F.Paste")
			(net "GND")
		)
	)
)
